# Thunderbolt GPU Adapter — assets/stackup.csv
Name;Type;Material;Thickness[mm];Constant
F.Mask;Top Solder Mask;;0.01;
F.Cu;copper;;0.035;
dielectric 1;prepreg;PR2116;0.12;4.12
In1.Cu;copper;;0.018;
dielectric 2;core;FR4-Improved;0.51;4.125
In2.Cu;copper;;0.018;
dielectric 3;prepreg;PR1080;0.14;4.125
In3.Cu;copper;;0.018;
dielectric 4;core;FR4-Improved;0.51;4.125
In4.Cu;copper;;0.018;
dielectric 5;prepreg;PR2116;0.12;4.12
B.Cu;copper;;0.035;
B.Mask;Bottom Solder Mask;;0.01;
